(kicad_pcb
	(version 20260206)
	(generator "pcbnew")
	(generator_version "10.0")
	(general
		(thickness 1.6)
		(legacy_teardrops no)
	)
	(paper "A4")
	(title_block
		(title "baseboard — 13948-1b.1110WZS1818.brd")
		(comment 1 "Honey Badger (Wiwynn) / footprints 906-911 of 2523")
	)
	(layers
		(0 "F.Cu" signal "TOP")
		(4 "In1.Cu" signal "L2GND")
		(6 "In2.Cu" signal "L3")
		(8 "In3.Cu" signal "L4VCC")
		(10 "In4.Cu" signal "L5VCC")
		(12 "In5.Cu" signal "L6")
		(14 "In6.Cu" signal "L7GND")
		(2 "B.Cu" signal "BOTTOM")
		(9 "F.Adhes" user "F.Adhesive")
		(11 "B.Adhes" user "B.Adhesive")
		(13 "F.Paste" user "Package Geometry/Pastemask Top")
		(15 "B.Paste" user "Package Geometry/Pastemask Bottom")
		(5 "F.SilkS" user "Ref Des/Silkscreen Top")
		(7 "B.SilkS" user "Ref Des/Silkscreen Bottom")
		(1 "F.Mask" user "Board Geometry/Soldermask Top")
		(3 "B.Mask" user "Board Geometry/Soldermask Bottom")
		(17 "Dwgs.User" user "User.Drawings")
		(19 "Cmts.User" user "User.Comments")
		(21 "Eco1.User" user "User.Eco1")
		(23 "Eco2.User" user "User.Eco2")
		(25 "Edge.Cuts" user "Board Geometry/Outline")
		(27 "Margin" user)
		(31 "F.CrtYd" user "Package Geometry/Place Bound Top")
		(29 "B.CrtYd" user "Package Geometry/Place Bound Bottom")
		(35 "F.Fab" user "Ref Des/Assembly Top")
		(33 "B.Fab" user "Ref Des/Assembly Bottom")
	)
	(footprint ""
		(layer "F.Cu")
		(at 23.445216 -213.79688 180)
		(property "Reference" "R632"
			(at 0 0 180)
			(layer "F.SilkS")
			(hide yes)
			(effects
				(font
					(size 1.27 1.27)
				)
			)
		)
		(property "Value" "4K7R2F-GP"
			(at 0.064008 -3.993896 180)
			(unlocked yes)
			(layer "F.Fab")
			(hide yes)
			(effects
				(font
					(size 1.016 1.016)
					(thickness 0.1524)
				)
			)
		)
		(property "Device Type" "R402H16"
			(at 0.064008 -5.517896 180)
			(unlocked yes)
			(layer "F.Fab")
			(hide yes)
			(effects
				(font
					(size 1.016 1.016)
					(thickness 0.1524)
				)
			)
		)
		(duplicate_pad_numbers_are_jumpers no)
		(fp_line
			(start 0.508 -0.9398)
			(end -0.508 -0.9398)
			(stroke
				(width 0.1524)
				(type default)
			)
			(layer "F.SilkS")
		)
		(fp_line
			(start -0.508 -0.9398)
			(end -0.508 0.9398)
			(stroke
				(width 0.1524)
				(type default)
			)
			(layer "F.SilkS")
		)
		(fp_rect
			(start -0.508 0.9398)
			(end 0.508 -0.9398)
			(stroke
				(width 0)
				(type default)
			)
			(fill no)
			(layer "F.CrtYd")
		)
		(fp_rect
			(start -0.508 0.9398)
			(end 0.508 -0.9398)
			(stroke
				(width 0)
				(type default)
			)
			(fill no)
			(layer "F.Fab")
		)
		(pad "1" smd custom
			(at 0 -0.4445 180)
			(size 0.1397 0.1397)
			(layers "F.Cu" "F.Mask" "F.Paste")
			(net "P3V3_STBY")
			(options
				(clearance outline)
				(anchor circle)
			)
			(primitives
				(gr_poly
					(pts
						(arc
							(start -0.1778 -0.2794)
							(mid -0.249642 -0.249642)
							(end -0.2794 -0.1778)
						)
						(arc
							(start -0.2794 0.1778)
							(mid -0.249642 0.249642)
							(end -0.1778 0.2794)
						)
						(arc
							(start 0.1778 0.2794)
							(mid 0.249642 0.249642)
							(end 0.2794 0.1778)
						)
						(arc
							(start 0.2794 -0.1778)
							(mid 0.249642 -0.249642)
							(end 0.1778 -0.2794)
						)
					)
					(width 0)
					(fill yes)
				)
			)
		)
		(pad "2" smd custom
			(at 0 0.4445 180)
			(size 0.1397 0.1397)
			(layers "F.Cu" "F.Mask" "F.Paste")
			(net "IO_EXP_HDD_PWR_A1")
			(options
				(clearance outline)
				(anchor circle)
			)
			(primitives
				(gr_poly
					(pts
						(arc
							(start -0.1778 -0.2794)
							(mid -0.249642 -0.249642)
							(end -0.2794 -0.1778)
						)
						(arc
							(start -0.2794 0.1778)
							(mid -0.249642 0.249642)
							(end -0.1778 0.2794)
						)
						(arc
							(start 0.1778 0.2794)
							(mid 0.249642 0.249642)
							(end 0.2794 0.1778)
						)
						(arc
							(start 0.2794 -0.1778)
							(mid 0.249642 -0.249642)
							(end 0.1778 -0.2794)
						)
					)
					(width 0)
					(fill yes)
				)
			)
		)
	)
	(footprint ""
		(layer "F.Cu")
		(at 92.27947 -104.14 90)
		(property "Reference" "SR817"
			(at 0 0 90)
			(layer "F.SilkS")
			(hide yes)
			(effects
				(font
					(size 1.27 1.27)
				)
			)
		)
		(property "Value" "4K75R2F-1-GP"
			(at 0.064008 -3.993896 90)
			(unlocked yes)
			(layer "F.Fab")
			(hide yes)
			(effects
				(font
					(size 1.016 1.016)
					(thickness 0.1524)
				)
			)
		)
		(property "Device Type" "R402H16"
			(at 0.064008 -5.517896 90)
			(unlocked yes)
			(layer "F.Fab")
			(hide yes)
			(effects
				(font
					(size 1.016 1.016)
					(thickness 0.1524)
				)
			)
		)
		(duplicate_pad_numbers_are_jumpers no)
		(fp_line
			(start 0.508 -0.9398)
			(end -0.508 -0.9398)
			(stroke
				(width 0.1524)
				(type default)
			)
			(layer "F.SilkS")
		)
		(fp_line
			(start -0.508 -0.9398)
			(end -0.508 0.9398)
			(stroke
				(width 0.1524)
				(type default)
			)
			(layer "F.SilkS")
		)
		(fp_rect
			(start -0.508 0.9398)
			(end 0.508 -0.9398)
			(stroke
				(width 0)
				(type default)
			)
			(fill no)
			(layer "F.CrtYd")
		)
		(fp_rect
			(start -0.508 0.9398)
			(end 0.508 -0.9398)
			(stroke
				(width 0)
				(type default)
			)
			(fill no)
			(layer "F.Fab")
		)
		(pad "1" smd custom
			(at 0 -0.4445 90)
			(size 0.1397 0.1397)
			(layers "F.Cu" "F.Mask" "F.Paste")
			(net "P1V8_E")
			(options
				(clearance outline)
				(anchor circle)
			)
			(primitives
				(gr_poly
					(pts
						(arc
							(start -0.1778 -0.2794)
							(mid -0.249642 -0.249642)
							(end -0.2794 -0.1778)
						)
						(arc
							(start -0.2794 0.1778)
							(mid -0.249642 0.249642)
							(end -0.1778 0.2794)
						)
						(arc
							(start 0.1778 0.2794)
							(mid 0.249642 0.249642)
							(end 0.2794 0.1778)
						)
						(arc
							(start 0.2794 -0.1778)
							(mid 0.249642 -0.249642)
							(end 0.1778 -0.2794)
						)
					)
					(width 0)
					(fill yes)
				)
			)
		)
		(pad "2" smd custom
			(at 0 0.4445 90)
			(size 0.1397 0.1397)
			(layers "F.Cu" "F.Mask" "F.Paste")
			(net "SDB_TX")
			(options
				(clearance outline)
				(anchor circle)
			)
			(primitives
				(gr_poly
					(pts
						(arc
							(start -0.1778 -0.2794)
							(mid -0.249642 -0.249642)
							(end -0.2794 -0.1778)
						)
						(arc
							(start -0.2794 0.1778)
							(mid -0.249642 0.249642)
							(end -0.1778 0.2794)
						)
						(arc
							(start 0.1778 0.2794)
							(mid 0.249642 0.249642)
							(end 0.2794 0.1778)
						)
						(arc
							(start 0.2794 -0.1778)
							(mid 0.249642 -0.249642)
							(end 0.1778 -0.2794)
						)
					)
					(width 0)
					(fill yes)
				)
			)
		)
	)
	(footprint ""
		(layer "F.Cu")
		(at 274.193 -183.515 90)
		(property "Reference" "R354"
			(at 0 0 90)
			(layer "F.SilkS")
			(hide yes)
			(effects
				(font
					(size 1.27 1.27)
				)
			)
		)
		(property "Value" "3K3R2F-2-GP"
			(at 0.064008 -3.993896 90)
			(unlocked yes)
			(layer "F.Fab")
			(hide yes)
			(effects
				(font
					(size 1.016 1.016)
					(thickness 0.1524)
				)
			)
		)
		(property "Device Type" "R402H16"
			(at 0.064008 -5.517896 90)
			(unlocked yes)
			(layer "F.Fab")
			(hide yes)
			(effects
				(font
					(size 1.016 1.016)
					(thickness 0.1524)
				)
			)
		)
		(duplicate_pad_numbers_are_jumpers no)
		(fp_line
			(start 0.508 -0.9398)
			(end -0.508 -0.9398)
			(stroke
				(width 0.1524)
				(type default)
			)
			(layer "F.SilkS")
		)
		(fp_line
			(start -0.508 -0.9398)
			(end -0.508 0.9398)
			(stroke
				(width 0.1524)
				(type default)
			)
			(layer "F.SilkS")
		)
		(fp_rect
			(start -0.508 0.9398)
			(end 0.508 -0.9398)
			(stroke
				(width 0)
				(type default)
			)
			(fill no)
			(layer "F.CrtYd")
		)
		(fp_rect
			(start -0.508 0.9398)
			(end 0.508 -0.9398)
			(stroke
				(width 0)
				(type default)
			)
			(fill no)
			(layer "F.Fab")
		)
		(pad "1" smd custom
			(at 0 -0.4445 90)
			(size 0.1397 0.1397)
			(layers "F.Cu" "F.Mask" "F.Paste")
			(net "P3V3_STBY")
			(options
				(clearance outline)
				(anchor circle)
			)
			(primitives
				(gr_poly
					(pts
						(arc
							(start -0.1778 -0.2794)
							(mid -0.249642 -0.249642)
							(end -0.2794 -0.1778)
						)
						(arc
							(start -0.2794 0.1778)
							(mid -0.249642 0.249642)
							(end -0.1778 0.2794)
						)
						(arc
							(start 0.1778 0.2794)
							(mid 0.249642 0.249642)
							(end 0.2794 0.1778)
						)
						(arc
							(start 0.2794 -0.1778)
							(mid 0.249642 -0.249642)
							(end 0.1778 -0.2794)
						)
					)
					(width 0)
					(fill yes)
				)
			)
		)
		(pad "2" smd custom
			(at 0 0.4445 90)
			(size 0.1397 0.1397)
			(layers "F.Cu" "F.Mask" "F.Paste")
			(net "ROMD3")
			(options
				(clearance outline)
				(anchor circle)
			)
			(primitives
				(gr_poly
					(pts
						(arc
							(start -0.1778 -0.2794)
							(mid -0.249642 -0.249642)
							(end -0.2794 -0.1778)
						)
						(arc
							(start -0.2794 0.1778)
							(mid -0.249642 0.249642)
							(end -0.1778 0.2794)
						)
						(arc
							(start 0.1778 0.2794)
							(mid 0.249642 0.249642)
							(end 0.2794 0.1778)
						)
						(arc
							(start 0.2794 -0.1778)
							(mid 0.249642 -0.249642)
							(end 0.1778 -0.2794)
						)
					)
					(width 0)
					(fill yes)
				)
			)
		)
	)
	(footprint ""
		(layer "F.Cu")
		(at 309.118 -160.655 180)
		(property "Reference" "R260"
			(at 0 0 180)
			(layer "F.SilkS")
			(hide yes)
			(effects
				(font
					(size 1.27 1.27)
				)
			)
		)
		(property "Value" "10KR2F-2-GP"
			(at 0.064008 -3.993896 180)
			(unlocked yes)
			(layer "F.Fab")
			(hide yes)
			(effects
				(font
					(size 1.016 1.016)
					(thickness 0.1524)
				)
			)
		)
		(property "Device Type" "R402H16"
			(at 0.064008 -5.517896 180)
			(unlocked yes)
			(layer "F.Fab")
			(hide yes)
			(effects
				(font
					(size 1.016 1.016)
					(thickness 0.1524)
				)
			)
		)
		(duplicate_pad_numbers_are_jumpers no)
		(fp_line
			(start 0.508 -0.9398)
			(end -0.508 -0.9398)
			(stroke
				(width 0.1524)
				(type default)
			)
			(layer "F.SilkS")
		)
		(fp_line
			(start -0.508 -0.9398)
			(end -0.508 0.9398)
			(stroke
				(width 0.1524)
				(type default)
			)
			(layer "F.SilkS")
		)
		(fp_rect
			(start -0.508 0.9398)
			(end 0.508 -0.9398)
			(stroke
				(width 0)
				(type default)
			)
			(fill no)
			(layer "F.CrtYd")
		)
		(fp_rect
			(start -0.508 0.9398)
			(end 0.508 -0.9398)
			(stroke
				(width 0)
				(type default)
			)
			(fill no)
			(layer "F.Fab")
		)
		(pad "1" smd custom
			(at 0 -0.4445 180)
			(size 0.1397 0.1397)
			(layers "F.Cu" "F.Mask" "F.Paste")
			(net "P3V3_STBY")
			(options
				(clearance outline)
				(anchor circle)
			)
			(primitives
				(gr_poly
					(pts
						(arc
							(start -0.1778 -0.2794)
							(mid -0.249642 -0.249642)
							(end -0.2794 -0.1778)
						)
						(arc
							(start -0.2794 0.1778)
							(mid -0.249642 0.249642)
							(end -0.1778 0.2794)
						)
						(arc
							(start 0.1778 0.2794)
							(mid 0.249642 0.249642)
							(end 0.2794 0.1778)
						)
						(arc
							(start 0.2794 -0.1778)
							(mid 0.249642 -0.249642)
							(end 0.1778 -0.2794)
						)
					)
					(width 0)
					(fill yes)
				)
			)
		)
		(pad "2" smd custom
			(at 0 0.4445 180)
			(size 0.1397 0.1397)
			(layers "F.Cu" "F.Mask" "F.Paste")
			(net "PU_BMC0_SCL11")
			(options
				(clearance outline)
				(anchor circle)
			)
			(primitives
				(gr_poly
					(pts
						(arc
							(start -0.1778 -0.2794)
							(mid -0.249642 -0.249642)
							(end -0.2794 -0.1778)
						)
						(arc
							(start -0.2794 0.1778)
							(mid -0.249642 0.249642)
							(end -0.1778 0.2794)
						)
						(arc
							(start 0.1778 0.2794)
							(mid 0.249642 0.249642)
							(end 0.2794 0.1778)
						)
						(arc
							(start 0.2794 -0.1778)
							(mid 0.249642 -0.249642)
							(end 0.1778 -0.2794)
						)
					)
					(width 0)
					(fill yes)
				)
			)
		)
	)
	(footprint ""
		(layer "F.Cu")
		(at 80.76819 -62.705488)
		(property "Reference" "SR710"
			(at 0 0 0)
			(layer "F.SilkS")
			(hide yes)
			(effects
				(font
					(size 1.27 1.27)
				)
			)
		)
		(property "Value" "10R2F-L-GP"
			(at 0.064008 -3.993896 0)
			(unlocked yes)
			(layer "F.Fab")
			(hide yes)
			(effects
				(font
					(size 1.016 1.016)
					(thickness 0.1524)
				)
			)
		)
		(property "Device Type" "R402H14"
			(at 0.064008 -5.517896 0)
			(unlocked yes)
			(layer "F.Fab")
			(hide yes)
			(effects
				(font
					(size 1.016 1.016)
					(thickness 0.1524)
				)
			)
		)
		(duplicate_pad_numbers_are_jumpers no)
		(fp_line
			(start -0.508 -0.9398)
			(end -0.508 0.9398)
			(stroke
				(width 0.1524)
				(type default)
			)
			(layer "F.SilkS")
		)
		(fp_line
			(start 0.508 -0.9398)
			(end -0.508 -0.9398)
			(stroke
				(width 0.1524)
				(type default)
			)
			(layer "F.SilkS")
		)
		(fp_rect
			(start -0.508 0.9398)
			(end 0.508 -0.9398)
			(stroke
				(width 0)
				(type default)
			)
			(fill no)
			(layer "F.CrtYd")
		)
		(fp_rect
			(start -0.508 0.9398)
			(end 0.508 -0.9398)
			(stroke
				(width 0)
				(type default)
			)
			(fill no)
			(layer "F.Fab")
		)
		(pad "1" smd custom
			(at 0 -0.4445)
			(size 0.1397 0.1397)
			(layers "F.Cu" "F.Mask" "F.Paste")
			(net "P1V8_C")
			(options
				(clearance outline)
				(anchor circle)
			)
			(primitives
				(gr_poly
					(pts
						(arc
							(start -0.1778 -0.2794)
							(mid -0.249642 -0.249642)
							(end -0.2794 -0.1778)
						)
						(arc
							(start -0.2794 0.1778)
							(mid -0.249642 0.249642)
							(end -0.1778 0.2794)
						)
						(arc
							(start 0.1778 0.2794)
							(mid 0.249642 0.249642)
							(end 0.2794 0.1778)
						)
						(arc
							(start 0.2794 -0.1778)
							(mid 0.249642 -0.249642)
							(end 0.1778 -0.2794)
						)
					)
					(width 0)
					(fill yes)
				)
			)
		)
		(pad "2" smd custom
			(at 0 0.4445)
			(size 0.1397 0.1397)
			(layers "F.Cu" "F.Mask" "F.Paste")
			(net "SYS_PLL_VDD")
			(options
				(clearance outline)
				(anchor circle)
			)
			(primitives
				(gr_poly
					(pts
						(arc
							(start -0.1778 -0.2794)
							(mid -0.249642 -0.249642)
							(end -0.2794 -0.1778)
						)
						(arc
							(start -0.2794 0.1778)
							(mid -0.249642 0.249642)
							(end -0.1778 0.2794)
						)
						(arc
							(start 0.1778 0.2794)
							(mid 0.249642 0.249642)
							(end 0.2794 0.1778)
						)
						(arc
							(start 0.2794 -0.1778)
							(mid 0.249642 -0.249642)
							(end 0.1778 -0.2794)
						)
					)
					(width 0)
					(fill yes)
				)
			)
		)
	)
	(footprint ""
		(layer "F.Cu")
		(at 216.281 -96.139 -90)
		(property "Reference" "PC139"
			(at 0 0 270)
			(layer "F.SilkS")
			(hide yes)
			(effects
				(font
					(size 1.27 1.27)
				)
			)
		)
		(property "Value" "SC10U6D3V5KX-1GP"
			(at -0.0762 -6.1214 270)
			(unlocked yes)
			(layer "F.Fab")
			(hide yes)
			(effects
				(font
					(size 1.016 1.016)
					(thickness 0.1524)
				)
			)
		)
		(property "Device Type" "C805H54"
			(at -0.0762 -8.1534 270)
			(unlocked yes)
			(layer "F.Fab")
			(hide yes)
			(effects
				(font
					(size 1.016 1.016)
					(thickness 0.1524)
				)
			)
		)
		(duplicate_pad_numbers_are_jumpers no)
		(fp_line
			(start 0.635 0)
			(end -0.635 0)
			(stroke
				(width 0.508)
				(type default)
			)
			(layer "F.SilkS")
		)
		(fp_rect
			(start -0.9652 1.778)
			(end 0.9652 -1.778)
			(stroke
				(width 0)
				(type default)
			)
			(fill no)
			(layer "F.CrtYd")
		)
		(fp_poly
			(pts
				(xy -0.9652 -1.778) (xy 0.9652 -1.778) (xy 0.9652 1.778) (xy -0.9652 1.778)
			)
			(stroke
				(width 0)
				(type default)
			)
			(fill no)
			(layer "F.Fab")
		)
		(pad "1" smd rect
			(at 0 -0.9652 270)
			(size 1.397 1.143)
			(layers "F.Cu" "F.Mask" "F.Paste")
			(net "TPS74801_P1V5_C_IN")
		)
		(pad "2" smd rect
			(at 0 0.9652 270)
			(size 1.397 1.143)
			(layers "F.Cu" "F.Mask" "F.Paste")
			(net "GND")
		)
	)
)
